(kicad_pcb
	(version 20260206)
	(generator "pcbnew")
	(generator_version "10.0")
	(general
		(thickness 1.6)
		(legacy_teardrops no)
	)
	(paper "A4")
	(title_block
		(title "12092022_DA0F0TMDCD0_F0T_Management_Board_D_brd_V3_OCP.brd")
		(comment 1 "Grand Teton / footprints 774-779 of 1440")
	)
	(layers
		(0 "F.Cu" signal "TOP")
		(4 "In1.Cu" signal "GND")
		(6 "In2.Cu" signal "IN1")
		(8 "In3.Cu" signal "GND1")
		(10 "In4.Cu" signal "IN2")
		(12 "In5.Cu" signal "VCC")
		(14 "In6.Cu" signal "VCC1")
		(16 "In7.Cu" signal "IN3")
		(18 "In8.Cu" signal "GND2")
		(20 "In9.Cu" signal "IN4")
		(22 "In10.Cu" signal "GND3")
		(2 "B.Cu" signal "BOTTOM")
		(9 "F.Adhes" user "F.Adhesive")
		(11 "B.Adhes" user "B.Adhesive")
		(13 "F.Paste" user "Package Geometry/Pastemask Top")
		(15 "B.Paste" user "Package Geometry/Pastemask Bottom")
		(5 "F.SilkS" user "Ref Des/Silkscreen Top")
		(7 "B.SilkS" user "Ref Des/Silkscreen Bottom")
		(1 "F.Mask" user "Board Geometry/Soldermask Top")
		(3 "B.Mask" user "Board Geometry/Soldermask Bottom")
		(17 "Dwgs.User" user "User.Drawings")
		(19 "Cmts.User" user "User.Comments")
		(21 "Eco1.User" user "User.Eco1")
		(23 "Eco2.User" user "User.Eco2")
		(25 "Edge.Cuts" user "Board Geometry/Outline")
		(27 "Margin" user)
		(31 "F.CrtYd" user "Package Geometry/Place Bound Top")
		(29 "B.CrtYd" user "Package Geometry/Place Bound Bottom")
		(35 "F.Fab" user "Ref Des/Assembly Top")
		(33 "B.Fab" user "Ref Des/Assembly Bottom")
	)
	(footprint ""
		(layer "B.Cu")
		(at 33.001712 -36.076128 90)
		(property "Reference" "C204"
			(at 0 0 90)
			(layer "B.SilkS")
			(hide yes)
			(effects
				(font
					(size 1.27 1.27)
				)
				(justify mirror)
			)
		)
		(property "Value" ""
			(at 0 0 90)
			(layer "B.Fab")
			(effects
				(font
					(size 1.27 1.27)
				)
				(justify mirror)
			)
		)
		(duplicate_pad_numbers_are_jumpers no)
		(fp_line
			(start 1.2954 -0.5842)
			(end -1.2954 -0.5842)
			(stroke
				(width 0.1524)
				(type default)
			)
			(layer "B.SilkS")
		)
		(fp_line
			(start 0 -0.5842)
			(end 0 0.5842)
			(stroke
				(width 0.1524)
				(type default)
			)
			(layer "B.SilkS")
		)
		(fp_line
			(start -1.2954 -0.5842)
			(end -1.2954 0.5842)
			(stroke
				(width 0.1524)
				(type default)
			)
			(layer "B.SilkS")
		)
		(fp_line
			(start 1.2954 0.5842)
			(end 1.2954 -0.5842)
			(stroke
				(width 0.1524)
				(type default)
			)
			(layer "B.SilkS")
		)
		(fp_line
			(start -1.2954 0.5842)
			(end 1.2954 0.5842)
			(stroke
				(width 0.1524)
				(type default)
			)
			(layer "B.SilkS")
		)
		(fp_line
			(start 0.8636 -0.4572)
			(end -0.8636 -0.4572)
			(stroke
				(width 0.1)
				(type default)
			)
			(layer "B.Fab")
		)
		(fp_line
			(start -0.8636 -0.4572)
			(end -0.8636 -0.4064)
			(stroke
				(width 0.1)
				(type default)
			)
			(layer "B.Fab")
		)
		(fp_line
			(start 1.1938 -0.4064)
			(end 0.8636 -0.4064)
			(stroke
				(width 0.1)
				(type default)
			)
			(layer "B.Fab")
		)
		(fp_line
			(start 0.8636 -0.4064)
			(end 0.8636 -0.4572)
			(stroke
				(width 0.1)
				(type default)
			)
			(layer "B.Fab")
		)
		(fp_line
			(start -0.8636 -0.4064)
			(end -1.1938 -0.4064)
			(stroke
				(width 0.1)
				(type default)
			)
			(layer "B.Fab")
		)
		(fp_line
			(start -1.1938 -0.4064)
			(end -1.1938 0.4064)
			(stroke
				(width 0.1)
				(type default)
			)
			(layer "B.Fab")
		)
		(fp_line
			(start 1.1938 0.4064)
			(end 1.1938 -0.4064)
			(stroke
				(width 0.1)
				(type default)
			)
			(layer "B.Fab")
		)
		(fp_line
			(start 0.8636 0.4064)
			(end 1.1938 0.4064)
			(stroke
				(width 0.1)
				(type default)
			)
			(layer "B.Fab")
		)
		(fp_line
			(start -0.8636 0.4064)
			(end -0.8636 0.4572)
			(stroke
				(width 0.1)
				(type default)
			)
			(layer "B.Fab")
		)
		(fp_line
			(start -1.1938 0.4064)
			(end -0.8636 0.4064)
			(stroke
				(width 0.1)
				(type default)
			)
			(layer "B.Fab")
		)
		(fp_line
			(start 0.8636 0.4572)
			(end 0.8636 0.4064)
			(stroke
				(width 0.1)
				(type default)
			)
			(layer "B.Fab")
		)
		(fp_line
			(start -0.8636 0.4572)
			(end 0.8636 0.4572)
			(stroke
				(width 0.1)
				(type default)
			)
			(layer "B.Fab")
		)
		(pad "1" smd rect
			(at 0.7366 0)
			(size 0.7112 0.8128)
			(layers "B.Cu" "B.Mask" "B.Paste")
			(net "CRT_VCC5")
		)
		(pad "2" smd rect
			(at -0.7366 0)
			(size 0.7112 0.8128)
			(layers "B.Cu" "B.Mask" "B.Paste")
			(net "GND")
		)
	)
	(footprint ""
		(layer "B.Cu")
		(at 69.166994 -37.05479 90)
		(property "Reference" "L5"
			(at 0 0 90)
			(layer "B.SilkS")
			(hide yes)
			(effects
				(font
					(size 1.27 1.27)
				)
				(justify mirror)
			)
		)
		(property "Value" ""
			(at 0 0 90)
			(layer "B.Fab")
			(effects
				(font
					(size 1.27 1.27)
				)
				(justify mirror)
			)
		)
		(duplicate_pad_numbers_are_jumpers no)
		(fp_line
			(start 1.27 -0.5842)
			(end -1.27 -0.5842)
			(stroke
				(width 0.1524)
				(type default)
			)
			(layer "B.SilkS")
		)
		(fp_line
			(start 1.27 -0.5588)
			(end 1.27 -0.5842)
			(stroke
				(width 0.1524)
				(type default)
			)
			(layer "B.SilkS")
		)
		(fp_line
			(start 1.27 0.5842)
			(end 1.27 -0.5842)
			(stroke
				(width 0.1524)
				(type default)
			)
			(layer "B.SilkS")
		)
		(fp_line
			(start 0.127 0.5842)
			(end 0.127 -0.5842)
			(stroke
				(width 0.1524)
				(type default)
			)
			(layer "B.SilkS")
		)
		(fp_line
			(start -0.127 0.5842)
			(end -0.127 -0.5842)
			(stroke
				(width 0.1524)
				(type default)
			)
			(layer "B.SilkS")
		)
		(fp_line
			(start -1.27 0.5842)
			(end -1.27 -0.5842)
			(stroke
				(width 0.1524)
				(type default)
			)
			(layer "B.SilkS")
		)
		(fp_line
			(start -1.27 0.5842)
			(end 1.27 0.5842)
			(stroke
				(width 0.1524)
				(type default)
			)
			(layer "B.SilkS")
		)
		(fp_line
			(start 0.9144 -0.508)
			(end -0.9144 -0.508)
			(stroke
				(width 0.1)
				(type default)
			)
			(layer "B.Fab")
		)
		(fp_line
			(start -0.9144 -0.508)
			(end -0.9144 -0.406654)
			(stroke
				(width 0.1)
				(type default)
			)
			(layer "B.Fab")
		)
		(fp_line
			(start 1.194308 -0.406654)
			(end 0.9144 -0.406654)
			(stroke
				(width 0.1)
				(type default)
			)
			(layer "B.Fab")
		)
		(fp_line
			(start 0.9144 -0.406654)
			(end 0.9144 -0.508)
			(stroke
				(width 0.1)
				(type default)
			)
			(layer "B.Fab")
		)
		(fp_line
			(start -0.9144 -0.406654)
			(end -1.1938 -0.406654)
			(stroke
				(width 0.1)
				(type default)
			)
			(layer "B.Fab")
		)
		(fp_line
			(start -1.1938 -0.406654)
			(end -1.1938 0.4064)
			(stroke
				(width 0.1)
				(type default)
			)
			(layer "B.Fab")
		)
		(fp_line
			(start -0.9144 0.4064)
			(end -0.9144 0.508)
			(stroke
				(width 0.1)
				(type default)
			)
			(layer "B.Fab")
		)
		(fp_line
			(start -1.1938 0.4064)
			(end -0.9144 0.4064)
			(stroke
				(width 0.1)
				(type default)
			)
			(layer "B.Fab")
		)
		(fp_line
			(start 1.194308 0.406654)
			(end 1.194308 -0.406654)
			(stroke
				(width 0.1)
				(type default)
			)
			(layer "B.Fab")
		)
		(fp_line
			(start 0.9144 0.406654)
			(end 1.194308 0.406654)
			(stroke
				(width 0.1)
				(type default)
			)
			(layer "B.Fab")
		)
		(fp_line
			(start 0.9144 0.508)
			(end 0.9144 0.406654)
			(stroke
				(width 0.1)
				(type default)
			)
			(layer "B.Fab")
		)
		(fp_line
			(start -0.9144 0.508)
			(end 0.9144 0.508)
			(stroke
				(width 0.1)
				(type default)
			)
			(layer "B.Fab")
		)
		(pad "1" smd rect
			(at 0.7366 0)
			(size 0.7112 0.8128)
			(layers "B.Cu" "B.Mask" "B.Paste")
			(net "P1V8_AUX")
		)
		(pad "2" smd rect
			(at -0.7366 0)
			(size 0.7112 0.8128)
			(layers "B.Cu" "B.Mask" "B.Paste")
			(net "P1V8_STBY_AVDDPLL")
		)
	)
	(footprint ""
		(layer "B.Cu")
		(at 51.5366 -34.671 90)
		(property "Reference" "R221"
			(at 0 0 90)
			(layer "B.SilkS")
			(hide yes)
			(effects
				(font
					(size 1.27 1.27)
				)
				(justify mirror)
			)
		)
		(property "Value" ""
			(at 0 0 90)
			(layer "B.Fab")
			(effects
				(font
					(size 1.27 1.27)
				)
				(justify mirror)
			)
		)
		(duplicate_pad_numbers_are_jumpers no)
		(fp_line
			(start 0.7874 -0.4064)
			(end -0.7874 -0.4064)
			(stroke
				(width 0.1524)
				(type default)
			)
			(layer "B.SilkS")
		)
		(fp_line
			(start -0.7874 -0.4064)
			(end -0.7874 0.4064)
			(stroke
				(width 0.1524)
				(type default)
			)
			(layer "B.SilkS")
		)
		(fp_line
			(start 0.7874 0.4064)
			(end 0.7874 -0.4064)
			(stroke
				(width 0.1524)
				(type default)
			)
			(layer "B.SilkS")
		)
		(fp_line
			(start -0.7874 0.4064)
			(end 0.7874 0.4064)
			(stroke
				(width 0.1524)
				(type default)
			)
			(layer "B.SilkS")
		)
		(fp_line
			(start 0.67945 -0.305054)
			(end 0.12065 -0.305054)
			(stroke
				(width 0.1)
				(type default)
			)
			(layer "B.Fab")
		)
		(fp_line
			(start 0.12065 -0.305054)
			(end 0.12065 -0.2794)
			(stroke
				(width 0.1)
				(type default)
			)
			(layer "B.Fab")
		)
		(fp_line
			(start -0.12065 -0.3048)
			(end -0.67945 -0.3048)
			(stroke
				(width 0.1)
				(type default)
			)
			(layer "B.Fab")
		)
		(fp_line
			(start -0.67945 -0.3048)
			(end -0.67945 0.3048)
			(stroke
				(width 0.1)
				(type default)
			)
			(layer "B.Fab")
		)
		(fp_line
			(start 0.12065 -0.2794)
			(end -0.12065 -0.2794)
			(stroke
				(width 0.1)
				(type default)
			)
			(layer "B.Fab")
		)
		(fp_line
			(start -0.12065 -0.2794)
			(end -0.12065 -0.3048)
			(stroke
				(width 0.1)
				(type default)
			)
			(layer "B.Fab")
		)
		(fp_line
			(start 0.12065 0.2794)
			(end 0.12065 0.3048)
			(stroke
				(width 0.1)
				(type default)
			)
			(layer "B.Fab")
		)
		(fp_line
			(start -0.120396 0.2794)
			(end 0.12065 0.2794)
			(stroke
				(width 0.1)
				(type default)
			)
			(layer "B.Fab")
		)
		(fp_line
			(start 0.67945 0.3048)
			(end 0.67945 -0.305054)
			(stroke
				(width 0.1)
				(type default)
			)
			(layer "B.Fab")
		)
		(fp_line
			(start 0.12065 0.3048)
			(end 0.67945 0.3048)
			(stroke
				(width 0.1)
				(type default)
			)
			(layer "B.Fab")
		)
		(fp_line
			(start -0.120396 0.3048)
			(end -0.120396 0.2794)
			(stroke
				(width 0.1)
				(type default)
			)
			(layer "B.Fab")
		)
		(fp_line
			(start -0.67945 0.3048)
			(end -0.120396 0.3048)
			(stroke
				(width 0.1)
				(type default)
			)
			(layer "B.Fab")
		)
		(pad "1" smd circle
			(at 0.40005 0 270)
			(size 0 0)
			(layers "B.Cu" "B.Mask" "B.Paste")
			(net "JTAG_1_BMC_TRST_R")
		)
		(pad "2" smd circle
			(at -0.40005 0 270)
			(size 0 0)
			(layers "B.Cu" "B.Mask" "B.Paste")
			(net "JTAG_MB_TRST_N")
		)
	)
	(footprint ""
		(layer "B.Cu")
		(at 15.113 -20.447 90)
		(property "Reference" "C326"
			(at 0 0 90)
			(layer "B.SilkS")
			(hide yes)
			(effects
				(font
					(size 1.27 1.27)
				)
				(justify mirror)
			)
		)
		(property "Value" ""
			(at 0 0 90)
			(layer "B.Fab")
			(effects
				(font
					(size 1.27 1.27)
				)
				(justify mirror)
			)
		)
		(duplicate_pad_numbers_are_jumpers no)
		(fp_line
			(start 0.7874 -0.4064)
			(end -0.7874 -0.4064)
			(stroke
				(width 0.1524)
				(type default)
			)
			(layer "B.SilkS")
		)
		(fp_line
			(start -0.7874 -0.4064)
			(end -0.7874 0.4064)
			(stroke
				(width 0.1524)
				(type default)
			)
			(layer "B.SilkS")
		)
		(fp_line
			(start 0.7874 0.4064)
			(end 0.7874 -0.4064)
			(stroke
				(width 0.1524)
				(type default)
			)
			(layer "B.SilkS")
		)
		(fp_line
			(start -0.7874 0.4064)
			(end 0.7874 0.4064)
			(stroke
				(width 0.1524)
				(type default)
			)
			(layer "B.SilkS")
		)
		(fp_line
			(start 0.67945 -0.305054)
			(end 0.12065 -0.305054)
			(stroke
				(width 0.1)
				(type default)
			)
			(layer "B.Fab")
		)
		(fp_line
			(start 0.12065 -0.305054)
			(end 0.12065 -0.2794)
			(stroke
				(width 0.1)
				(type default)
			)
			(layer "B.Fab")
		)
		(fp_line
			(start -0.12065 -0.3048)
			(end -0.67945 -0.3048)
			(stroke
				(width 0.1)
				(type default)
			)
			(layer "B.Fab")
		)
		(fp_line
			(start -0.67945 -0.3048)
			(end -0.67945 0.3048)
			(stroke
				(width 0.1)
				(type default)
			)
			(layer "B.Fab")
		)
		(fp_line
			(start 0.12065 -0.2794)
			(end -0.12065 -0.2794)
			(stroke
				(width 0.1)
				(type default)
			)
			(layer "B.Fab")
		)
		(fp_line
			(start -0.12065 -0.2794)
			(end -0.12065 -0.3048)
			(stroke
				(width 0.1)
				(type default)
			)
			(layer "B.Fab")
		)
		(fp_line
			(start 0.12065 0.2794)
			(end 0.12065 0.3048)
			(stroke
				(width 0.1)
				(type default)
			)
			(layer "B.Fab")
		)
		(fp_line
			(start -0.120396 0.2794)
			(end 0.12065 0.2794)
			(stroke
				(width 0.1)
				(type default)
			)
			(layer "B.Fab")
		)
		(fp_line
			(start 0.67945 0.3048)
			(end 0.67945 -0.305054)
			(stroke
				(width 0.1)
				(type default)
			)
			(layer "B.Fab")
		)
		(fp_line
			(start 0.12065 0.3048)
			(end 0.67945 0.3048)
			(stroke
				(width 0.1)
				(type default)
			)
			(layer "B.Fab")
		)
		(fp_line
			(start -0.120396 0.3048)
			(end -0.120396 0.2794)
			(stroke
				(width 0.1)
				(type default)
			)
			(layer "B.Fab")
		)
		(fp_line
			(start -0.67945 0.3048)
			(end -0.120396 0.3048)
			(stroke
				(width 0.1)
				(type default)
			)
			(layer "B.Fab")
		)
		(pad "1" smd circle
			(at 0.40005 0 270)
			(size 0 0)
			(layers "B.Cu" "B.Mask" "B.Paste")
			(net "PWR_LED_BUF_N_R")
		)
		(pad "2" smd circle
			(at -0.40005 0 270)
			(size 0 0)
			(layers "B.Cu" "B.Mask" "B.Paste")
			(net "GND")
		)
	)
	(footprint ""
		(layer "B.Cu")
		(at 84.08924 -53.413152 180)
		(property "Reference" "R325"
			(at 0 0 0)
			(layer "B.SilkS")
			(hide yes)
			(effects
				(font
					(size 1.27 1.27)
				)
				(justify mirror)
			)
		)
		(property "Value" ""
			(at 0 0 0)
			(layer "B.Fab")
			(effects
				(font
					(size 1.27 1.27)
				)
				(justify mirror)
			)
		)
		(duplicate_pad_numbers_are_jumpers no)
		(fp_line
			(start 0.7874 0.4064)
			(end 0.7874 -0.4064)
			(stroke
				(width 0.1524)
				(type default)
			)
			(layer "B.SilkS")
		)
		(fp_line
			(start 0.7874 -0.4064)
			(end -0.7874 -0.4064)
			(stroke
				(width 0.1524)
				(type default)
			)
			(layer "B.SilkS")
		)
		(fp_line
			(start -0.7874 0.4064)
			(end 0.7874 0.4064)
			(stroke
				(width 0.1524)
				(type default)
			)
			(layer "B.SilkS")
		)
		(fp_line
			(start -0.7874 -0.4064)
			(end -0.7874 0.4064)
			(stroke
				(width 0.1524)
				(type default)
			)
			(layer "B.SilkS")
		)
		(fp_line
			(start 0.67945 0.3048)
			(end 0.67945 -0.305054)
			(stroke
				(width 0.1)
				(type default)
			)
			(layer "B.Fab")
		)
		(fp_line
			(start 0.67945 -0.305054)
			(end 0.12065 -0.305054)
			(stroke
				(width 0.1)
				(type default)
			)
			(layer "B.Fab")
		)
		(fp_line
			(start 0.12065 0.3048)
			(end 0.67945 0.3048)
			(stroke
				(width 0.1)
				(type default)
			)
			(layer "B.Fab")
		)
		(fp_line
			(start 0.12065 0.2794)
			(end 0.12065 0.3048)
			(stroke
				(width 0.1)
				(type default)
			)
			(layer "B.Fab")
		)
		(fp_line
			(start 0.12065 -0.2794)
			(end -0.12065 -0.2794)
			(stroke
				(width 0.1)
				(type default)
			)
			(layer "B.Fab")
		)
		(fp_line
			(start 0.12065 -0.305054)
			(end 0.12065 -0.2794)
			(stroke
				(width 0.1)
				(type default)
			)
			(layer "B.Fab")
		)
		(fp_line
			(start -0.120396 0.3048)
			(end -0.120396 0.2794)
			(stroke
				(width 0.1)
				(type default)
			)
			(layer "B.Fab")
		)
		(fp_line
			(start -0.120396 0.2794)
			(end 0.12065 0.2794)
			(stroke
				(width 0.1)
				(type default)
			)
			(layer "B.Fab")
		)
		(fp_line
			(start -0.12065 -0.2794)
			(end -0.12065 -0.3048)
			(stroke
				(width 0.1)
				(type default)
			)
			(layer "B.Fab")
		)
		(fp_line
			(start -0.12065 -0.3048)
			(end -0.67945 -0.3048)
			(stroke
				(width 0.1)
				(type default)
			)
			(layer "B.Fab")
		)
		(fp_line
			(start -0.67945 0.3048)
			(end -0.120396 0.3048)
			(stroke
				(width 0.1)
				(type default)
			)
			(layer "B.Fab")
		)
		(fp_line
			(start -0.67945 -0.3048)
			(end -0.67945 0.3048)
			(stroke
				(width 0.1)
				(type default)
			)
			(layer "B.Fab")
		)
		(pad "1" smd circle
			(at 0.40005 0)
			(size 0 0)
			(layers "B.Cu" "B.Mask" "B.Paste")
			(net "P0V6_DDR_VREF_AUX")
		)
		(pad "2" smd circle
			(at -0.40005 0)
			(size 0 0)
			(layers "B.Cu" "B.Mask" "B.Paste")
			(net "GND")
		)
	)
	(footprint ""
		(layer "B.Cu")
		(at 51.816 -30.861 -90)
		(property "Reference" "R229"
			(at 0 0 90)
			(layer "B.SilkS")
			(hide yes)
			(effects
				(font
					(size 1.27 1.27)
				)
				(justify mirror)
			)
		)
		(property "Value" ""
			(at 0 0 90)
			(layer "B.Fab")
			(effects
				(font
					(size 1.27 1.27)
				)
				(justify mirror)
			)
		)
		(duplicate_pad_numbers_are_jumpers no)
		(fp_line
			(start -0.7874 0.4064)
			(end 0.7874 0.4064)
			(stroke
				(width 0.1524)
				(type default)
			)
			(layer "B.SilkS")
		)
		(fp_line
			(start 0.7874 0.4064)
			(end 0.7874 -0.4064)
			(stroke
				(width 0.1524)
				(type default)
			)
			(layer "B.SilkS")
		)
		(fp_line
			(start -0.7874 -0.4064)
			(end -0.7874 0.4064)
			(stroke
				(width 0.1524)
				(type default)
			)
			(layer "B.SilkS")
		)
		(fp_line
			(start 0.7874 -0.4064)
			(end -0.7874 -0.4064)
			(stroke
				(width 0.1524)
				(type default)
			)
			(layer "B.SilkS")
		)
		(fp_line
			(start -0.67945 0.3048)
			(end -0.120396 0.3048)
			(stroke
				(width 0.1)
				(type default)
			)
			(layer "B.Fab")
		)
		(fp_line
			(start -0.120396 0.3048)
			(end -0.120396 0.2794)
			(stroke
				(width 0.1)
				(type default)
			)
			(layer "B.Fab")
		)
		(fp_line
			(start 0.12065 0.3048)
			(end 0.67945 0.3048)
			(stroke
				(width 0.1)
				(type default)
			)
			(layer "B.Fab")
		)
		(fp_line
			(start 0.67945 0.3048)
			(end 0.67945 -0.305054)
			(stroke
				(width 0.1)
				(type default)
			)
			(layer "B.Fab")
		)
		(fp_line
			(start -0.120396 0.2794)
			(end 0.12065 0.2794)
			(stroke
				(width 0.1)
				(type default)
			)
			(layer "B.Fab")
		)
		(fp_line
			(start 0.12065 0.2794)
			(end 0.12065 0.3048)
			(stroke
				(width 0.1)
				(type default)
			)
			(layer "B.Fab")
		)
		(fp_line
			(start -0.12065 -0.2794)
			(end -0.12065 -0.3048)
			(stroke
				(width 0.1)
				(type default)
			)
			(layer "B.Fab")
		)
		(fp_line
			(start 0.12065 -0.2794)
			(end -0.12065 -0.2794)
			(stroke
				(width 0.1)
				(type default)
			)
			(layer "B.Fab")
		)
		(fp_line
			(start -0.67945 -0.3048)
			(end -0.67945 0.3048)
			(stroke
				(width 0.1)
				(type default)
			)
			(layer "B.Fab")
		)
		(fp_line
			(start -0.12065 -0.3048)
			(end -0.67945 -0.3048)
			(stroke
				(width 0.1)
				(type default)
			)
			(layer "B.Fab")
		)
		(fp_line
			(start 0.12065 -0.305054)
			(end 0.12065 -0.2794)
			(stroke
				(width 0.1)
				(type default)
			)
			(layer "B.Fab")
		)
		(fp_line
			(start 0.67945 -0.305054)
			(end 0.12065 -0.305054)
			(stroke
				(width 0.1)
				(type default)
			)
			(layer "B.Fab")
		)
		(pad "1" smd circle
			(at 0.40005 0 90)
			(size 0 0)
			(layers "B.Cu" "B.Mask" "B.Paste")
			(net "GND")
		)
		(pad "2" smd circle
			(at -0.40005 0 90)
			(size 0 0)
			(layers "B.Cu" "B.Mask" "B.Paste")
			(net "JTAG_MB_TRST_N")
		)
	)
)
